# T6G (Grand Teton) — schematic netlist excerpt (pin names and nets, part order shuffled) for the footprints in the layout excerpt that follows; sources: Cadence DE-HDL packaged netlist, KiCad conversion of 04192023_DAF0TMB3IC0_F0TG_MB_C_brd_V02_OCP.brd

R1452  Q_RES  10K 5% CHIP  pkg 0402LF  page 259 : A = P1V8_AUX ; B = PWRGD_P12V_MEM_CPU1
C1863  Q_CAP  0.1UF 25V 10% X7R  pkg 0402  page 111 : A = P3V3_AUX ; B = GND
C729  Q_CAP_DIFFBUS  DIFF BUS_0.22UF 6.3V 20% X6S  pkg C0201  page 66 : \1\ = P5E_CPU1_P1_TX_C_DP<6> ; \2\ = P5E_CPU1_P1_TX_DP<6>

(kicad_pcb
	(version 20260206)
	(generator "pcbnew")
	(generator_version "10.0")
	(general
		(thickness 1.6)
		(legacy_teardrops no)
	)
	(paper "A4")
	(title_block
		(title "04192023_DAF0TMB3IC0_F0TG_MB_C_brd_V02_OCP.brd")
		(comment 1 "Grand Teton / footprints 921-923 of 8354")
	)
	(layers
		(0 "F.Cu" signal "TOP")
		(4 "In1.Cu" signal "GND")
		(6 "In2.Cu" signal "IN1")
		(8 "In3.Cu" signal "GND1")
		(10 "In4.Cu" signal "IN2")
		(12 "In5.Cu" signal "GND2")
		(14 "In6.Cu" signal "IN3")
		(16 "In7.Cu" signal "GND3")
		(18 "In8.Cu" signal "VCC")
		(20 "In9.Cu" signal "VCC1")
		(22 "In10.Cu" signal "GND4")
		(24 "In11.Cu" signal "IN4")
		(26 "In12.Cu" signal "GND5")
		(28 "In13.Cu" signal "IN5")
		(30 "In14.Cu" signal "GND6")
		(32 "In15.Cu" signal "IN6")
		(34 "In16.Cu" signal "GND7")
		(2 "B.Cu" signal "BOTTOM")
		(9 "F.Adhes" user "F.Adhesive")
		(11 "B.Adhes" user "B.Adhesive")
		(13 "F.Paste" user "Package Geometry/Pastemask Top")
		(15 "B.Paste" user "Package Geometry/Pastemask Bottom")
		(5 "F.SilkS" user "Ref Des/Silkscreen Top")
		(7 "B.SilkS" user "Ref Des/Silkscreen Bottom")
		(1 "F.Mask" user "Board Geometry/Soldermask Top")
		(3 "B.Mask" user "Board Geometry/Soldermask Bottom")
		(17 "Dwgs.User" user "User.Drawings")
		(19 "Cmts.User" user "User.Comments")
		(21 "Eco1.User" user "User.Eco1")
		(23 "Eco2.User" user "User.Eco2")
		(25 "Edge.Cuts" user "Board Geometry/Outline")
		(27 "Margin" user)
		(31 "F.CrtYd" user "Package Geometry/Place Bound Top")
		(29 "B.CrtYd" user "Package Geometry/Place Bound Bottom")
		(35 "F.Fab" user "Ref Des/Assembly Top")
		(33 "B.Fab" user "Ref Des/Assembly Bottom")
	)
	(footprint ""
		(layer "F.Cu")
		(at 31.712662 -421.916098 180)
		(property "Reference" "C1863"
			(at 0 0 180)
			(layer "F.SilkS")
			(hide yes)
			(effects
				(font
					(size 1.27 1.27)
				)
			)
		)
		(property "Value" ""
			(at 0 0 180)
			(layer "F.Fab")
			(effects
				(font
					(size 1.27 1.27)
				)
			)
		)
		(duplicate_pad_numbers_are_jumpers no)
		(fp_line
			(start 0.7874 0.4064)
			(end -0.7874 0.4064)
			(stroke
				(width 0.1524)
				(type default)
			)
			(layer "F.SilkS")
		)
		(fp_line
			(start 0.7874 -0.4064)
			(end 0.7874 0.4064)
			(stroke
				(width 0.1524)
				(type default)
			)
			(layer "F.SilkS")
		)
		(fp_line
			(start -0.7874 0.4064)
			(end -0.7874 -0.4064)
			(stroke
				(width 0.1524)
				(type default)
			)
			(layer "F.SilkS")
		)
		(fp_line
			(start -0.7874 -0.4064)
			(end 0.7874 -0.4064)
			(stroke
				(width 0.1524)
				(type default)
			)
			(layer "F.SilkS")
		)
		(fp_line
			(start 0.67945 0.3048)
			(end 0.120396 0.3048)
			(stroke
				(width 0.1)
				(type default)
			)
			(layer "F.Fab")
		)
		(fp_line
			(start 0.67945 -0.3048)
			(end 0.67945 0.3048)
			(stroke
				(width 0.1)
				(type default)
			)
			(layer "F.Fab")
		)
		(fp_line
			(start 0.12065 -0.2794)
			(end 0.12065 -0.3048)
			(stroke
				(width 0.1)
				(type default)
			)
			(layer "F.Fab")
		)
		(fp_line
			(start 0.12065 -0.3048)
			(end 0.67945 -0.3048)
			(stroke
				(width 0.1)
				(type default)
			)
			(layer "F.Fab")
		)
		(fp_line
			(start 0.120396 0.3048)
			(end 0.120396 0.2794)
			(stroke
				(width 0.1)
				(type default)
			)
			(layer "F.Fab")
		)
		(fp_line
			(start 0.120396 0.2794)
			(end -0.12065 0.2794)
			(stroke
				(width 0.1)
				(type default)
			)
			(layer "F.Fab")
		)
		(fp_line
			(start -0.12065 0.3048)
			(end -0.67945 0.3048)
			(stroke
				(width 0.1)
				(type default)
			)
			(layer "F.Fab")
		)
		(fp_line
			(start -0.12065 0.2794)
			(end -0.12065 0.3048)
			(stroke
				(width 0.1)
				(type default)
			)
			(layer "F.Fab")
		)
		(fp_line
			(start -0.12065 -0.2794)
			(end 0.12065 -0.2794)
			(stroke
				(width 0.1)
				(type default)
			)
			(layer "F.Fab")
		)
		(fp_line
			(start -0.12065 -0.305054)
			(end -0.12065 -0.2794)
			(stroke
				(width 0.1)
				(type default)
			)
			(layer "F.Fab")
		)
		(fp_line
			(start -0.67945 0.3048)
			(end -0.67945 -0.305054)
			(stroke
				(width 0.1)
				(type default)
			)
			(layer "F.Fab")
		)
		(fp_line
			(start -0.67945 -0.305054)
			(end -0.12065 -0.305054)
			(stroke
				(width 0.1)
				(type default)
			)
			(layer "F.Fab")
		)
		(pad "1" smd circle
			(at -0.40005 0 180)
			(size 0 0)
			(layers "F.Cu" "F.Mask" "F.Paste")
			(net "P3V3_AUX")
		)
		(pad "2" smd circle
			(at 0.40005 0 180)
			(size 0 0)
			(layers "F.Cu" "F.Mask" "F.Paste")
			(net "GND")
		)
	)
	(footprint ""
		(layer "F.Cu")
		(at 84.026502 -370.57203 -90)
		(property "Reference" "C729"
			(at 0 0 270)
			(layer "F.SilkS")
			(hide yes)
			(effects
				(font
					(size 1.27 1.27)
				)
			)
		)
		(property "Value" ""
			(at 0 0 270)
			(layer "F.Fab")
			(effects
				(font
					(size 1.27 1.27)
				)
			)
		)
		(duplicate_pad_numbers_are_jumpers no)
		(fp_line
			(start -0.299974 0.150114)
			(end -0.299974 -0.150114)
			(stroke
				(width 0.1)
				(type default)
			)
			(layer "F.Fab")
		)
		(fp_line
			(start 0.299974 0.150114)
			(end -0.299974 0.150114)
			(stroke
				(width 0.1)
				(type default)
			)
			(layer "F.Fab")
		)
		(fp_line
			(start -0.299974 -0.150114)
			(end 0.299974 -0.150114)
			(stroke
				(width 0.1)
				(type default)
			)
			(layer "F.Fab")
		)
		(fp_line
			(start 0.299974 -0.150114)
			(end 0.299974 0.150114)
			(stroke
				(width 0.1)
				(type default)
			)
			(layer "F.Fab")
		)
		(pad "1" smd rect
			(at -0.2667 0 270)
			(size 0.3048 0.381)
			(layers "F.Cu" "F.Mask" "F.Paste")
			(net "P5E_CPU1_P1_TX_C_DP<6>")
		)
		(pad "2" smd rect
			(at 0.2667 0 270)
			(size 0.3048 0.381)
			(layers "F.Cu" "F.Mask" "F.Paste")
			(net "P5E_CPU1_P1_TX_DP<6>")
		)
	)
	(footprint ""
		(layer "F.Cu")
		(at 104.389936 -127.768096 -90)
		(property "Reference" "R1452"
			(at 0 0 270)
			(layer "F.SilkS")
			(hide yes)
			(effects
				(font
					(size 1.27 1.27)
				)
			)
		)
		(property "Value" ""
			(at 0 0 270)
			(layer "F.Fab")
			(effects
				(font
					(size 1.27 1.27)
				)
			)
		)
		(duplicate_pad_numbers_are_jumpers no)
		(fp_line
			(start -0.7874 0.4064)
			(end -0.7874 -0.4064)
			(stroke
				(width 0.1524)
				(type default)
			)
			(layer "F.SilkS")
		)
		(fp_line
			(start 0.7874 0.4064)
			(end -0.7874 0.4064)
			(stroke
				(width 0.1524)
				(type default)
			)
			(layer "F.SilkS")
		)
		(fp_line
			(start -0.7874 -0.4064)
			(end 0.7874 -0.4064)
			(stroke
				(width 0.1524)
				(type default)
			)
			(layer "F.SilkS")
		)
		(fp_line
			(start 0.7874 -0.4064)
			(end 0.7874 0.4064)
			(stroke
				(width 0.1524)
				(type default)
			)
			(layer "F.SilkS")
		)
		(fp_line
			(start -0.67945 0.3048)
			(end -0.67945 -0.305054)
			(stroke
				(width 0.1)
				(type default)
			)
			(layer "F.Fab")
		)
		(fp_line
			(start -0.12065 0.3048)
			(end -0.67945 0.3048)
			(stroke
				(width 0.1)
				(type default)
			)
			(layer "F.Fab")
		)
		(fp_line
			(start 0.120396 0.3048)
			(end 0.120396 0.2794)
			(stroke
				(width 0.1)
				(type default)
			)
			(layer "F.Fab")
		)
		(fp_line
			(start 0.67945 0.3048)
			(end 0.120396 0.3048)
			(stroke
				(width 0.1)
				(type default)
			)
			(layer "F.Fab")
		)
		(fp_line
			(start -0.12065 0.2794)
			(end -0.12065 0.3048)
			(stroke
				(width 0.1)
				(type default)
			)
			(layer "F.Fab")
		)
		(fp_line
			(start 0.120396 0.2794)
			(end -0.12065 0.2794)
			(stroke
				(width 0.1)
				(type default)
			)
			(layer "F.Fab")
		)
		(fp_line
			(start -0.12065 -0.2794)
			(end 0.12065 -0.2794)
			(stroke
				(width 0.1)
				(type default)
			)
			(layer "F.Fab")
		)
		(fp_line
			(start 0.12065 -0.2794)
			(end 0.12065 -0.3048)
			(stroke
				(width 0.1)
				(type default)
			)
			(layer "F.Fab")
		)
		(fp_line
			(start 0.12065 -0.3048)
			(end 0.67945 -0.3048)
			(stroke
				(width 0.1)
				(type default)
			)
			(layer "F.Fab")
		)
		(fp_line
			(start 0.67945 -0.3048)
			(end 0.67945 0.3048)
			(stroke
				(width 0.1)
				(type default)
			)
			(layer "F.Fab")
		)
		(fp_line
			(start -0.67945 -0.305054)
			(end -0.12065 -0.305054)
			(stroke
				(width 0.1)
				(type default)
			)
			(layer "F.Fab")
		)
		(fp_line
			(start -0.12065 -0.305054)
			(end -0.12065 -0.2794)
			(stroke
				(width 0.1)
				(type default)
			)
			(layer "F.Fab")
		)
		(pad "1" smd circle
			(at -0.40005 0 270)
			(size 0 0)
			(layers "F.Cu" "F.Mask" "F.Paste")
			(net "P1V8_AUX")
		)
		(pad "2" smd circle
			(at 0.40005 0 270)
			(size 0 0)
			(layers "F.Cu" "F.Mask" "F.Paste")
			(net "PWRGD_P12V_MEM_CPU1")
		)
	)
)
